(kicad_pcb
	(version 20260206)
	(generator "pcbnew")
	(generator_version "10.0")
	(general
		(thickness 1.6)
		(legacy_teardrops no)
	)
	(paper "A4")
	(title_block
		(title "01162023_DA0F0TEBIF0_F0T_Expander_BD_F_brd_V02_OCP.brd")
		(comment 1 "Grand Teton / footprints 1604-1609 of 9728")
	)
	(layers
		(0 "F.Cu" signal "TOP")
		(4 "In1.Cu" signal "GND")
		(6 "In2.Cu" signal "VCC")
		(8 "In3.Cu" signal "VCC1")
		(10 "In4.Cu" signal "GND1")
		(12 "In5.Cu" signal "IN1")
		(14 "In6.Cu" signal "GND2")
		(16 "In7.Cu" signal "IN2")
		(18 "In8.Cu" signal "GND3")
		(20 "In9.Cu" signal "IN3")
		(22 "In10.Cu" signal "GND4")
		(24 "In11.Cu" signal "IN4")
		(26 "In12.Cu" signal "GND5")
		(28 "In13.Cu" signal "IN5")
		(30 "In14.Cu" signal "GND6")
		(32 "In15.Cu" signal "IN6")
		(34 "In16.Cu" signal "GND7")
		(2 "B.Cu" signal "BOTTOM")
		(9 "F.Adhes" user "F.Adhesive")
		(11 "B.Adhes" user "B.Adhesive")
		(13 "F.Paste" user "Package Geometry/Pastemask Top")
		(15 "B.Paste" user "Package Geometry/Pastemask Bottom")
		(5 "F.SilkS" user "Ref Des/Silkscreen Top")
		(7 "B.SilkS" user "Ref Des/Silkscreen Bottom")
		(1 "F.Mask" user "Board Geometry/Soldermask Top")
		(3 "B.Mask" user "Board Geometry/Soldermask Bottom")
		(17 "Dwgs.User" user "User.Drawings")
		(19 "Cmts.User" user "User.Comments")
		(21 "Eco1.User" user "User.Eco1")
		(23 "Eco2.User" user "User.Eco2")
		(25 "Edge.Cuts" user "Board Geometry/Outline")
		(27 "Margin" user)
		(31 "F.CrtYd" user "Package Geometry/Place Bound Top")
		(29 "B.CrtYd" user "Package Geometry/Place Bound Bottom")
		(35 "F.Fab" user "Ref Des/Assembly Top")
		(33 "B.Fab" user "Ref Des/Assembly Bottom")
	)
	(footprint ""
		(layer "F.Cu")
		(at 357.567738 -392.41984 90)
		(property "Reference" "R6695"
			(at 0 0 90)
			(layer "F.SilkS")
			(hide yes)
			(effects
				(font
					(size 1.27 1.27)
				)
			)
		)
		(property "Value" ""
			(at 0 0 90)
			(layer "F.Fab")
			(effects
				(font
					(size 1.27 1.27)
				)
			)
		)
		(duplicate_pad_numbers_are_jumpers no)
		(fp_line
			(start 0.7874 -0.4064)
			(end 0.7874 0.4064)
			(stroke
				(width 0.1524)
				(type default)
			)
			(layer "F.SilkS")
		)
		(fp_line
			(start -0.7874 -0.4064)
			(end 0.7874 -0.4064)
			(stroke
				(width 0.1524)
				(type default)
			)
			(layer "F.SilkS")
		)
		(fp_line
			(start 0.7874 0.4064)
			(end -0.7874 0.4064)
			(stroke
				(width 0.1524)
				(type default)
			)
			(layer "F.SilkS")
		)
		(fp_line
			(start -0.7874 0.4064)
			(end -0.7874 -0.4064)
			(stroke
				(width 0.1524)
				(type default)
			)
			(layer "F.SilkS")
		)
		(fp_line
			(start -0.12065 -0.305054)
			(end -0.12065 -0.2794)
			(stroke
				(width 0.1)
				(type default)
			)
			(layer "F.Fab")
		)
		(fp_line
			(start -0.67945 -0.305054)
			(end -0.12065 -0.305054)
			(stroke
				(width 0.1)
				(type default)
			)
			(layer "F.Fab")
		)
		(fp_line
			(start 0.67945 -0.3048)
			(end 0.67945 0.3048)
			(stroke
				(width 0.1)
				(type default)
			)
			(layer "F.Fab")
		)
		(fp_line
			(start 0.12065 -0.3048)
			(end 0.67945 -0.3048)
			(stroke
				(width 0.1)
				(type default)
			)
			(layer "F.Fab")
		)
		(fp_line
			(start 0.12065 -0.2794)
			(end 0.12065 -0.3048)
			(stroke
				(width 0.1)
				(type default)
			)
			(layer "F.Fab")
		)
		(fp_line
			(start -0.12065 -0.2794)
			(end 0.12065 -0.2794)
			(stroke
				(width 0.1)
				(type default)
			)
			(layer "F.Fab")
		)
		(fp_line
			(start 0.120396 0.2794)
			(end -0.12065 0.2794)
			(stroke
				(width 0.1)
				(type default)
			)
			(layer "F.Fab")
		)
		(fp_line
			(start -0.12065 0.2794)
			(end -0.12065 0.3048)
			(stroke
				(width 0.1)
				(type default)
			)
			(layer "F.Fab")
		)
		(fp_line
			(start 0.67945 0.3048)
			(end 0.120396 0.3048)
			(stroke
				(width 0.1)
				(type default)
			)
			(layer "F.Fab")
		)
		(fp_line
			(start 0.120396 0.3048)
			(end 0.120396 0.2794)
			(stroke
				(width 0.1)
				(type default)
			)
			(layer "F.Fab")
		)
		(fp_line
			(start -0.12065 0.3048)
			(end -0.67945 0.3048)
			(stroke
				(width 0.1)
				(type default)
			)
			(layer "F.Fab")
		)
		(fp_line
			(start -0.67945 0.3048)
			(end -0.67945 -0.305054)
			(stroke
				(width 0.1)
				(type default)
			)
			(layer "F.Fab")
		)
		(pad "1" smd circle
			(at -0.40005 0 90)
			(size 0 0)
			(layers "F.Cu" "F.Mask" "F.Paste")
			(net "MB_3V3IO_RSVD1_ISO")
		)
		(pad "2" smd circle
			(at 0.40005 0 90)
			(size 0 0)
			(layers "F.Cu" "F.Mask" "F.Paste")
			(net "P3V3_AUX")
		)
	)
	(footprint ""
		(layer "F.Cu")
		(at 293.992554 -158.080202 90)
		(property "Reference" "R3308"
			(at 0 0 90)
			(layer "F.SilkS")
			(hide yes)
			(effects
				(font
					(size 1.27 1.27)
				)
			)
		)
		(property "Value" ""
			(at 0 0 90)
			(layer "F.Fab")
			(effects
				(font
					(size 1.27 1.27)
				)
			)
		)
		(duplicate_pad_numbers_are_jumpers no)
		(fp_line
			(start 0.7874 -0.4064)
			(end 0.7874 0.4064)
			(stroke
				(width 0.1524)
				(type default)
			)
			(layer "F.SilkS")
		)
		(fp_line
			(start -0.7874 -0.4064)
			(end 0.7874 -0.4064)
			(stroke
				(width 0.1524)
				(type default)
			)
			(layer "F.SilkS")
		)
		(fp_line
			(start 0.7874 0.4064)
			(end -0.7874 0.4064)
			(stroke
				(width 0.1524)
				(type default)
			)
			(layer "F.SilkS")
		)
		(fp_line
			(start -0.7874 0.4064)
			(end -0.7874 -0.4064)
			(stroke
				(width 0.1524)
				(type default)
			)
			(layer "F.SilkS")
		)
		(fp_line
			(start -0.12065 -0.305054)
			(end -0.12065 -0.2794)
			(stroke
				(width 0.1)
				(type default)
			)
			(layer "F.Fab")
		)
		(fp_line
			(start -0.67945 -0.305054)
			(end -0.12065 -0.305054)
			(stroke
				(width 0.1)
				(type default)
			)
			(layer "F.Fab")
		)
		(fp_line
			(start 0.67945 -0.3048)
			(end 0.67945 0.3048)
			(stroke
				(width 0.1)
				(type default)
			)
			(layer "F.Fab")
		)
		(fp_line
			(start 0.12065 -0.3048)
			(end 0.67945 -0.3048)
			(stroke
				(width 0.1)
				(type default)
			)
			(layer "F.Fab")
		)
		(fp_line
			(start 0.12065 -0.2794)
			(end 0.12065 -0.3048)
			(stroke
				(width 0.1)
				(type default)
			)
			(layer "F.Fab")
		)
		(fp_line
			(start -0.12065 -0.2794)
			(end 0.12065 -0.2794)
			(stroke
				(width 0.1)
				(type default)
			)
			(layer "F.Fab")
		)
		(fp_line
			(start 0.120396 0.2794)
			(end -0.12065 0.2794)
			(stroke
				(width 0.1)
				(type default)
			)
			(layer "F.Fab")
		)
		(fp_line
			(start -0.12065 0.2794)
			(end -0.12065 0.3048)
			(stroke
				(width 0.1)
				(type default)
			)
			(layer "F.Fab")
		)
		(fp_line
			(start 0.67945 0.3048)
			(end 0.120396 0.3048)
			(stroke
				(width 0.1)
				(type default)
			)
			(layer "F.Fab")
		)
		(fp_line
			(start 0.120396 0.3048)
			(end 0.120396 0.2794)
			(stroke
				(width 0.1)
				(type default)
			)
			(layer "F.Fab")
		)
		(fp_line
			(start -0.12065 0.3048)
			(end -0.67945 0.3048)
			(stroke
				(width 0.1)
				(type default)
			)
			(layer "F.Fab")
		)
		(fp_line
			(start -0.67945 0.3048)
			(end -0.67945 -0.305054)
			(stroke
				(width 0.1)
				(type default)
			)
			(layer "F.Fab")
		)
		(pad "1" smd circle
			(at -0.40005 0 90)
			(size 0 0)
			(layers "F.Cu" "F.Mask" "F.Paste")
			(net "FM_SYS_THROTTLE_R")
		)
		(pad "2" smd circle
			(at 0.40005 0 90)
			(size 0 0)
			(layers "F.Cu" "F.Mask" "F.Paste")
			(net "FM_SYS_THROTTLE_NIC4")
		)
	)
	(footprint ""
		(layer "F.Cu")
		(at 171.983654 -61.487812 180)
		(property "Reference" "R5984"
			(at 0 0 180)
			(layer "F.SilkS")
			(hide yes)
			(effects
				(font
					(size 1.27 1.27)
				)
			)
		)
		(property "Value" ""
			(at 0 0 180)
			(layer "F.Fab")
			(effects
				(font
					(size 1.27 1.27)
				)
			)
		)
		(duplicate_pad_numbers_are_jumpers no)
		(fp_line
			(start 0.7874 0.4064)
			(end -0.7874 0.4064)
			(stroke
				(width 0.1524)
				(type default)
			)
			(layer "F.SilkS")
		)
		(fp_line
			(start 0.7874 -0.4064)
			(end 0.7874 0.4064)
			(stroke
				(width 0.1524)
				(type default)
			)
			(layer "F.SilkS")
		)
		(fp_line
			(start -0.7874 0.4064)
			(end -0.7874 -0.4064)
			(stroke
				(width 0.1524)
				(type default)
			)
			(layer "F.SilkS")
		)
		(fp_line
			(start -0.7874 -0.4064)
			(end 0.7874 -0.4064)
			(stroke
				(width 0.1524)
				(type default)
			)
			(layer "F.SilkS")
		)
		(fp_line
			(start 0.67945 0.3048)
			(end 0.120396 0.3048)
			(stroke
				(width 0.1)
				(type default)
			)
			(layer "F.Fab")
		)
		(fp_line
			(start 0.67945 -0.3048)
			(end 0.67945 0.3048)
			(stroke
				(width 0.1)
				(type default)
			)
			(layer "F.Fab")
		)
		(fp_line
			(start 0.12065 -0.2794)
			(end 0.12065 -0.3048)
			(stroke
				(width 0.1)
				(type default)
			)
			(layer "F.Fab")
		)
		(fp_line
			(start 0.12065 -0.3048)
			(end 0.67945 -0.3048)
			(stroke
				(width 0.1)
				(type default)
			)
			(layer "F.Fab")
		)
		(fp_line
			(start 0.120396 0.3048)
			(end 0.120396 0.2794)
			(stroke
				(width 0.1)
				(type default)
			)
			(layer "F.Fab")
		)
		(fp_line
			(start 0.120396 0.2794)
			(end -0.12065 0.2794)
			(stroke
				(width 0.1)
				(type default)
			)
			(layer "F.Fab")
		)
		(fp_line
			(start -0.12065 0.3048)
			(end -0.67945 0.3048)
			(stroke
				(width 0.1)
				(type default)
			)
			(layer "F.Fab")
		)
		(fp_line
			(start -0.12065 0.2794)
			(end -0.12065 0.3048)
			(stroke
				(width 0.1)
				(type default)
			)
			(layer "F.Fab")
		)
		(fp_line
			(start -0.12065 -0.2794)
			(end 0.12065 -0.2794)
			(stroke
				(width 0.1)
				(type default)
			)
			(layer "F.Fab")
		)
		(fp_line
			(start -0.12065 -0.305054)
			(end -0.12065 -0.2794)
			(stroke
				(width 0.1)
				(type default)
			)
			(layer "F.Fab")
		)
		(fp_line
			(start -0.67945 0.3048)
			(end -0.67945 -0.305054)
			(stroke
				(width 0.1)
				(type default)
			)
			(layer "F.Fab")
		)
		(fp_line
			(start -0.67945 -0.305054)
			(end -0.12065 -0.305054)
			(stroke
				(width 0.1)
				(type default)
			)
			(layer "F.Fab")
		)
		(pad "1" smd circle
			(at -0.40005 0 180)
			(size 0 0)
			(layers "F.Cu" "F.Mask" "F.Paste")
			(net "PWRGD_P12V_SSD6_D")
		)
		(pad "2" smd circle
			(at 0.40005 0 180)
			(size 0 0)
			(layers "F.Cu" "F.Mask" "F.Paste")
			(net "PWRGD_P12V_SSD6_R")
		)
	)
	(footprint ""
		(layer "F.Cu")
		(at 116.27739 -255.82372 180)
		(property "Reference" "PC45"
			(at 0 0 180)
			(layer "F.SilkS")
			(hide yes)
			(effects
				(font
					(size 1.27 1.27)
				)
			)
		)
		(property "Value" ""
			(at 0 0 180)
			(layer "F.Fab")
			(effects
				(font
					(size 1.27 1.27)
				)
			)
		)
		(duplicate_pad_numbers_are_jumpers no)
		(fp_line
			(start 0.7874 0.4064)
			(end -0.7874 0.4064)
			(stroke
				(width 0.1524)
				(type default)
			)
			(layer "F.SilkS")
		)
		(fp_line
			(start 0.7874 -0.4064)
			(end 0.7874 0.4064)
			(stroke
				(width 0.1524)
				(type default)
			)
			(layer "F.SilkS")
		)
		(fp_line
			(start -0.7874 0.4064)
			(end -0.7874 -0.4064)
			(stroke
				(width 0.1524)
				(type default)
			)
			(layer "F.SilkS")
		)
		(fp_line
			(start -0.7874 -0.4064)
			(end 0.7874 -0.4064)
			(stroke
				(width 0.1524)
				(type default)
			)
			(layer "F.SilkS")
		)
		(fp_line
			(start 0.67945 0.3048)
			(end 0.120396 0.3048)
			(stroke
				(width 0.1)
				(type default)
			)
			(layer "F.Fab")
		)
		(fp_line
			(start 0.67945 -0.3048)
			(end 0.67945 0.3048)
			(stroke
				(width 0.1)
				(type default)
			)
			(layer "F.Fab")
		)
		(fp_line
			(start 0.12065 -0.2794)
			(end 0.12065 -0.3048)
			(stroke
				(width 0.1)
				(type default)
			)
			(layer "F.Fab")
		)
		(fp_line
			(start 0.12065 -0.3048)
			(end 0.67945 -0.3048)
			(stroke
				(width 0.1)
				(type default)
			)
			(layer "F.Fab")
		)
		(fp_line
			(start 0.120396 0.3048)
			(end 0.120396 0.2794)
			(stroke
				(width 0.1)
				(type default)
			)
			(layer "F.Fab")
		)
		(fp_line
			(start 0.120396 0.2794)
			(end -0.12065 0.2794)
			(stroke
				(width 0.1)
				(type default)
			)
			(layer "F.Fab")
		)
		(fp_line
			(start -0.12065 0.3048)
			(end -0.67945 0.3048)
			(stroke
				(width 0.1)
				(type default)
			)
			(layer "F.Fab")
		)
		(fp_line
			(start -0.12065 0.2794)
			(end -0.12065 0.3048)
			(stroke
				(width 0.1)
				(type default)
			)
			(layer "F.Fab")
		)
		(fp_line
			(start -0.12065 -0.2794)
			(end 0.12065 -0.2794)
			(stroke
				(width 0.1)
				(type default)
			)
			(layer "F.Fab")
		)
		(fp_line
			(start -0.12065 -0.305054)
			(end -0.12065 -0.2794)
			(stroke
				(width 0.1)
				(type default)
			)
			(layer "F.Fab")
		)
		(fp_line
			(start -0.67945 0.3048)
			(end -0.67945 -0.305054)
			(stroke
				(width 0.1)
				(type default)
			)
			(layer "F.Fab")
		)
		(fp_line
			(start -0.67945 -0.305054)
			(end -0.12065 -0.305054)
			(stroke
				(width 0.1)
				(type default)
			)
			(layer "F.Fab")
		)
		(pad "1" smd circle
			(at -0.40005 0 180)
			(size 0 0)
			(layers "F.Cu" "F.Mask" "F.Paste")
			(net "P0V8_PEX0_VDD")
		)
		(pad "2" smd circle
			(at 0.40005 0 180)
			(size 0 0)
			(layers "F.Cu" "F.Mask" "F.Paste")
			(net "GND")
		)
	)
	(footprint ""
		(layer "F.Cu")
		(at 20.675092 -56.977534 180)
		(property "Reference" "PC390"
			(at 0 0 180)
			(layer "F.SilkS")
			(hide yes)
			(effects
				(font
					(size 1.27 1.27)
				)
			)
		)
		(property "Value" ""
			(at 0 0 180)
			(layer "F.Fab")
			(effects
				(font
					(size 1.27 1.27)
				)
			)
		)
		(duplicate_pad_numbers_are_jumpers no)
		(fp_line
			(start 0.7874 0.4064)
			(end -0.7874 0.4064)
			(stroke
				(width 0.1524)
				(type default)
			)
			(layer "F.SilkS")
		)
		(fp_line
			(start 0.7874 -0.4064)
			(end 0.7874 0.4064)
			(stroke
				(width 0.1524)
				(type default)
			)
			(layer "F.SilkS")
		)
		(fp_line
			(start -0.7874 0.4064)
			(end -0.7874 -0.4064)
			(stroke
				(width 0.1524)
				(type default)
			)
			(layer "F.SilkS")
		)
		(fp_line
			(start -0.7874 -0.4064)
			(end 0.7874 -0.4064)
			(stroke
				(width 0.1524)
				(type default)
			)
			(layer "F.SilkS")
		)
		(fp_line
			(start 0.67945 0.3048)
			(end 0.120396 0.3048)
			(stroke
				(width 0.1)
				(type default)
			)
			(layer "F.Fab")
		)
		(fp_line
			(start 0.67945 -0.3048)
			(end 0.67945 0.3048)
			(stroke
				(width 0.1)
				(type default)
			)
			(layer "F.Fab")
		)
		(fp_line
			(start 0.12065 -0.2794)
			(end 0.12065 -0.3048)
			(stroke
				(width 0.1)
				(type default)
			)
			(layer "F.Fab")
		)
		(fp_line
			(start 0.12065 -0.3048)
			(end 0.67945 -0.3048)
			(stroke
				(width 0.1)
				(type default)
			)
			(layer "F.Fab")
		)
		(fp_line
			(start 0.120396 0.3048)
			(end 0.120396 0.2794)
			(stroke
				(width 0.1)
				(type default)
			)
			(layer "F.Fab")
		)
		(fp_line
			(start 0.120396 0.2794)
			(end -0.12065 0.2794)
			(stroke
				(width 0.1)
				(type default)
			)
			(layer "F.Fab")
		)
		(fp_line
			(start -0.12065 0.3048)
			(end -0.67945 0.3048)
			(stroke
				(width 0.1)
				(type default)
			)
			(layer "F.Fab")
		)
		(fp_line
			(start -0.12065 0.2794)
			(end -0.12065 0.3048)
			(stroke
				(width 0.1)
				(type default)
			)
			(layer "F.Fab")
		)
		(fp_line
			(start -0.12065 -0.2794)
			(end 0.12065 -0.2794)
			(stroke
				(width 0.1)
				(type default)
			)
			(layer "F.Fab")
		)
		(fp_line
			(start -0.12065 -0.305054)
			(end -0.12065 -0.2794)
			(stroke
				(width 0.1)
				(type default)
			)
			(layer "F.Fab")
		)
		(fp_line
			(start -0.67945 0.3048)
			(end -0.67945 -0.305054)
			(stroke
				(width 0.1)
				(type default)
			)
			(layer "F.Fab")
		)
		(fp_line
			(start -0.67945 -0.305054)
			(end -0.12065 -0.305054)
			(stroke
				(width 0.1)
				(type default)
			)
			(layer "F.Fab")
		)
		(pad "1" smd circle
			(at -0.40005 0 180)
			(size 0 0)
			(layers "F.Cu" "F.Mask" "F.Paste")
			(net "P12V_AUX")
		)
		(pad "2" smd circle
			(at 0.40005 0 180)
			(size 0 0)
			(layers "F.Cu" "F.Mask" "F.Paste")
			(net "GND")
		)
	)
	(footprint ""
		(layer "F.Cu")
		(at 336.042 -145.923)
		(property "Reference" "R4795"
			(at 0 0 0)
			(layer "F.SilkS")
			(hide yes)
			(effects
				(font
					(size 1.27 1.27)
				)
			)
		)
		(property "Value" ""
			(at 0 0 0)
			(layer "F.Fab")
			(effects
				(font
					(size 1.27 1.27)
				)
			)
		)
		(duplicate_pad_numbers_are_jumpers no)
		(fp_line
			(start -0.7874 -0.4064)
			(end 0.7874 -0.4064)
			(stroke
				(width 0.1524)
				(type default)
			)
			(layer "F.SilkS")
		)
		(fp_line
			(start -0.7874 0.4064)
			(end -0.7874 -0.4064)
			(stroke
				(width 0.1524)
				(type default)
			)
			(layer "F.SilkS")
		)
		(fp_line
			(start 0.7874 -0.4064)
			(end 0.7874 0.4064)
			(stroke
				(width 0.1524)
				(type default)
			)
			(layer "F.SilkS")
		)
		(fp_line
			(start 0.7874 0.4064)
			(end -0.7874 0.4064)
			(stroke
				(width 0.1524)
				(type default)
			)
			(layer "F.SilkS")
		)
		(fp_line
			(start -0.67945 -0.305054)
			(end -0.12065 -0.305054)
			(stroke
				(width 0.1)
				(type default)
			)
			(layer "F.Fab")
		)
		(fp_line
			(start -0.67945 0.3048)
			(end -0.67945 -0.305054)
			(stroke
				(width 0.1)
				(type default)
			)
			(layer "F.Fab")
		)
		(fp_line
			(start -0.12065 -0.305054)
			(end -0.12065 -0.2794)
			(stroke
				(width 0.1)
				(type default)
			)
			(layer "F.Fab")
		)
		(fp_line
			(start -0.12065 -0.2794)
			(end 0.12065 -0.2794)
			(stroke
				(width 0.1)
				(type default)
			)
			(layer "F.Fab")
		)
		(fp_line
			(start -0.12065 0.2794)
			(end -0.12065 0.3048)
			(stroke
				(width 0.1)
				(type default)
			)
			(layer "F.Fab")
		)
		(fp_line
			(start -0.12065 0.3048)
			(end -0.67945 0.3048)
			(stroke
				(width 0.1)
				(type default)
			)
			(layer "F.Fab")
		)
		(fp_line
			(start 0.120396 0.2794)
			(end -0.12065 0.2794)
			(stroke
				(width 0.1)
				(type default)
			)
			(layer "F.Fab")
		)
		(fp_line
			(start 0.120396 0.3048)
			(end 0.120396 0.2794)
			(stroke
				(width 0.1)
				(type default)
			)
			(layer "F.Fab")
		)
		(fp_line
			(start 0.12065 -0.3048)
			(end 0.67945 -0.3048)
			(stroke
				(width 0.1)
				(type default)
			)
			(layer "F.Fab")
		)
		(fp_line
			(start 0.12065 -0.2794)
			(end 0.12065 -0.3048)
			(stroke
				(width 0.1)
				(type default)
			)
			(layer "F.Fab")
		)
		(fp_line
			(start 0.67945 -0.3048)
			(end 0.67945 0.3048)
			(stroke
				(width 0.1)
				(type default)
			)
			(layer "F.Fab")
		)
		(fp_line
			(start 0.67945 0.3048)
			(end 0.120396 0.3048)
			(stroke
				(width 0.1)
				(type default)
			)
			(layer "F.Fab")
		)
		(pad "1" smd circle
			(at -0.40005 0)
			(size 0 0)
			(layers "F.Cu" "F.Mask" "F.Paste")
			(net "P3V3_AUX")
		)
		(pad "2" smd circle
			(at 0.40005 0)
			(size 0 0)
			(layers "F.Cu" "F.Mask" "F.Paste")
			(net "RST_PEX_SSD14_PERST_R_N")
		)
	)
)
